(kicad_pcb
	(version 20260206)
	(generator "pcbnew")
	(generator_version "10.0")
	(general
		(thickness 1.6)
		(legacy_teardrops no)
	)
	(paper "A4")
	(title_block
		(title "4HDD Backplane_Layout.brd")
		(comment 1 "Tioga Pass / footprint 16 of 97 (SATA3), pads 1-32 of 32")
	)
	(layers
		(0 "F.Cu" signal "TOP")
		(4 "In1.Cu" signal "L2GND")
		(6 "In2.Cu" signal "L3")
		(8 "In3.Cu" signal "L4")
		(10 "In4.Cu" signal "L5GND")
		(2 "B.Cu" signal "BOTTOM")
		(9 "F.Adhes" user "F.Adhesive")
		(11 "B.Adhes" user "B.Adhesive")
		(13 "F.Paste" user "Package Geometry/Pastemask Top")
		(15 "B.Paste" user "Package Geometry/Pastemask Bottom")
		(5 "F.SilkS" user "Ref Des/Silkscreen Top")
		(7 "B.SilkS" user "Ref Des/Silkscreen Bottom")
		(1 "F.Mask" user "Board Geometry/Soldermask Top")
		(3 "B.Mask" user "Board Geometry/Soldermask Bottom")
		(17 "Dwgs.User" user "User.Drawings")
		(19 "Cmts.User" user "User.Comments")
		(21 "Eco1.User" user "User.Eco1")
		(23 "Eco2.User" user "User.Eco2")
		(25 "Edge.Cuts" user "Board Geometry/Outline")
		(27 "Margin" user)
		(31 "F.CrtYd" user "Package Geometry/Place Bound Top")
		(29 "B.CrtYd" user "Package Geometry/Place Bound Bottom")
		(35 "F.Fab" user "Ref Des/Assembly Top")
		(33 "B.Fab" user "Ref Des/Assembly Bottom")
	)
	(footprint ""
		(layer "F.Cu")
		(at 33.219898 -15.120112 180)
		(property "Reference" "SATA3"
			(at 0 0 180)
			(layer "F.SilkS")
			(hide yes)
			(effects
				(font
					(size 1.27 1.27)
				)
			)
		)
		(property "Value" "FCI-CONN29-2R-GP-U"
			(at -35.2552 -14.1859 180)
			(unlocked yes)
			(layer "F.Fab")
			(hide yes)
			(effects
				(font
					(size 1.016 1.016)
					(thickness 0.1524)
				)
			)
		)
		(property "Device Type" "PREFIT-29P-458055-UH395"
			(at -35.2552 -15.7099 180)
			(unlocked yes)
			(layer "F.Fab")
			(hide yes)
			(effects
				(font
					(size 1.016 1.016)
					(thickness 0.1524)
				)
			)
		)
		(duplicate_pad_numbers_are_jumpers no)
		(pad "" np_thru_hole circle
			(at -23.95474 0 180)
			(size 0.254 0.254)
			(drill 1.3462)
			(layers "*.Cu" "*.Mask")
			(clearance 0.9017)
			(thermal_gap 0.9017)
		)
		(pad "30" thru_hole circle
			(at -26.07945 0 180)
			(size 2.3622 2.3622)
			(drill 1.949958)
			(layers "*.Cu" "*.Mask")
			(remove_unused_layers no)
			(net "Net_63")
			(clearance 0.1524)
			(thermal_gap 0.1524)
		)
		(pad "31" thru_hole circle
			(at 15.91945 0 180)
			(size 2.3622 2.3622)
			(drill 1.949958)
			(layers "*.Cu" "*.Mask")
			(remove_unused_layers no)
			(net "Net_54")
			(clearance 0.1524)
			(thermal_gap 0.1524)
		)
		(pad "P1" thru_hole circle
			(at -3.175 -1.27 180)
			(size 0.8636 0.8636)
			(drill 0.499872)
			(layers "*.Cu" "*.Mask")
			(remove_unused_layers no)
			(net "Net_59")
			(clearance 0.1778)
			(thermal_gap 0.1778)
		)
		(pad "P2" thru_hole circle
			(at -4.445 -1.27 180)
			(size 0.8636 0.8636)
			(drill 0.499872)
			(layers "*.Cu" "*.Mask")
			(remove_unused_layers no)
			(net "Net_61")
			(clearance 0.1778)
			(thermal_gap 0.1778)
		)
		(pad "P3" thru_hole circle
			(at -5.715 -1.27 180)
			(size 0.8636 0.8636)
			(drill 0.499872)
			(layers "*.Cu" "*.Mask")
			(remove_unused_layers no)
			(net "Net_60")
			(clearance 0.1778)
			(thermal_gap 0.1778)
		)
		(pad "P4" thru_hole circle
			(at -6.985 -1.27 180)
			(size 0.8636 0.8636)
			(drill 0.499872)
			(layers "*.Cu" "*.Mask")
			(remove_unused_layers no)
			(net "GND")
			(clearance 0.1778)
			(thermal_gap 0.1778)
		)
		(pad "P5" thru_hole circle
			(at -8.255 -1.27 180)
			(size 0.8636 0.8636)
			(drill 0.499872)
			(layers "*.Cu" "*.Mask")
			(remove_unused_layers no)
			(net "GND")
			(clearance 0.1778)
			(thermal_gap 0.1778)
		)
		(pad "P6" thru_hole circle
			(at -9.525 -1.27 180)
			(size 0.8636 0.8636)
			(drill 0.499872)
			(layers "*.Cu" "*.Mask")
			(remove_unused_layers no)
			(net "GND")
			(clearance 0.1778)
			(thermal_gap 0.1778)
		)
		(pad "P7" thru_hole circle
			(at -10.795 -1.27 180)
			(size 0.8636 0.8636)
			(drill 0.499872)
			(layers "*.Cu" "*.Mask")
			(remove_unused_layers no)
			(net "5V_PRE_2")
			(clearance 0.1778)
			(thermal_gap 0.1778)
		)
		(pad "P8" thru_hole circle
			(at -12.065 -1.27 180)
			(size 0.8636 0.8636)
			(drill 0.499872)
			(layers "*.Cu" "*.Mask")
			(remove_unused_layers no)
			(net "P5V_SW_L")
			(clearance 0.1778)
			(thermal_gap 0.1778)
		)
		(pad "P9" thru_hole circle
			(at -13.335 -1.27 180)
			(size 0.8636 0.8636)
			(drill 0.499872)
			(layers "*.Cu" "*.Mask")
			(remove_unused_layers no)
			(net "P5V_SW_L")
			(clearance 0.1778)
			(thermal_gap 0.1778)
		)
		(pad "P10" thru_hole circle
			(at -14.605 -1.27 180)
			(size 0.8636 0.8636)
			(drill 0.499872)
			(layers "*.Cu" "*.Mask")
			(remove_unused_layers no)
			(net "HBA_PRSNT2_N")
			(clearance 0.1778)
			(thermal_gap 0.1778)
		)
		(pad "P11" thru_hole circle
			(at -15.875 -1.27 180)
			(size 0.8636 0.8636)
			(drill 0.499872)
			(layers "*.Cu" "*.Mask")
			(remove_unused_layers no)
			(net "HDD_ACT_LED2")
			(clearance 0.1778)
			(thermal_gap 0.1778)
		)
		(pad "P12" thru_hole circle
			(at -17.145 -1.27 180)
			(size 0.8636 0.8636)
			(drill 0.499872)
			(layers "*.Cu" "*.Mask")
			(remove_unused_layers no)
			(net "GND")
			(clearance 0.1778)
			(thermal_gap 0.1778)
		)
		(pad "P13" thru_hole circle
			(at -18.415 -1.27 180)
			(size 0.8636 0.8636)
			(drill 0.499872)
			(layers "*.Cu" "*.Mask")
			(remove_unused_layers no)
			(net "12V_PRE_2")
			(clearance 0.1778)
			(thermal_gap 0.1778)
		)
		(pad "P14" thru_hole circle
			(at -19.685 -1.27 180)
			(size 0.8636 0.8636)
			(drill 0.499872)
			(layers "*.Cu" "*.Mask")
			(remove_unused_layers no)
			(net "P12V_SW_L")
			(clearance 0.1778)
			(thermal_gap 0.1778)
		)
		(pad "P15" thru_hole circle
			(at -20.955 -1.27 180)
			(size 0.8636 0.8636)
			(drill 0.499872)
			(layers "*.Cu" "*.Mask")
			(remove_unused_layers no)
			(net "P12V_SW_L")
			(clearance 0.1778)
			(thermal_gap 0.1778)
		)
		(pad "S1" thru_hole circle
			(at 10.795 -1.27 180)
			(size 0.8636 0.8636)
			(drill 0.499872)
			(layers "*.Cu" "*.Mask")
			(remove_unused_layers no)
			(net "GND")
			(clearance 0.1778)
			(thermal_gap 0.1778)
		)
		(pad "S2" thru_hole circle
			(at 9.525 -1.27 180)
			(size 0.8636 0.8636)
			(drill 0.499872)
			(layers "*.Cu" "*.Mask")
			(remove_unused_layers no)
			(net "HBA_MB_TX_P2")
			(clearance 0.1778)
			(thermal_gap 0.1778)
		)
		(pad "S3" thru_hole circle
			(at 8.255 -1.27 180)
			(size 0.8636 0.8636)
			(drill 0.499872)
			(layers "*.Cu" "*.Mask")
			(remove_unused_layers no)
			(net "HBA_MB_TX_N2")
			(clearance 0.1778)
			(thermal_gap 0.1778)
		)
		(pad "S4" thru_hole circle
			(at 6.985 -1.27 180)
			(size 0.8636 0.8636)
			(drill 0.499872)
			(layers "*.Cu" "*.Mask")
			(remove_unused_layers no)
			(net "GND")
			(clearance 0.1778)
			(thermal_gap 0.1778)
		)
		(pad "S5" thru_hole circle
			(at 5.715 -1.27 180)
			(size 0.8636 0.8636)
			(drill 0.499872)
			(layers "*.Cu" "*.Mask")
			(remove_unused_layers no)
			(net "HBA_MB_RX_N2")
			(clearance 0.1778)
			(thermal_gap 0.1778)
		)
		(pad "S6" thru_hole circle
			(at 4.445 -1.27 180)
			(size 0.8636 0.8636)
			(drill 0.499872)
			(layers "*.Cu" "*.Mask")
			(remove_unused_layers no)
			(net "HBA_MB_RX_P2")
			(clearance 0.1778)
			(thermal_gap 0.1778)
		)
		(pad "S7" thru_hole circle
			(at 3.175 -1.27 180)
			(size 0.8636 0.8636)
			(drill 0.499872)
			(layers "*.Cu" "*.Mask")
			(remove_unused_layers no)
			(net "GND")
			(clearance 0.1778)
			(thermal_gap 0.1778)
		)
		(pad "S8" thru_hole oval
			(at 2.4003 2.13995 180)
			(size 0.6096 0.8128)
			(drill 0.399796)
			(layers "*.Cu" "*.Mask")
			(remove_unused_layers no)
			(net "GND")
			(clearance 0.254)
			(thermal_gap 0.254)
		)
		(pad "S9" thru_hole oval
			(at 1.6002 2.13995 180)
			(size 0.6096 0.8128)
			(drill 0.399796)
			(layers "*.Cu" "*.Mask")
			(remove_unused_layers no)
			(net "Net_58")
			(clearance 0.254)
			(thermal_gap 0.254)
		)
		(pad "S10" thru_hole oval
			(at 0.8001 2.13995 180)
			(size 0.6096 0.8128)
			(drill 0.399796)
			(layers "*.Cu" "*.Mask")
			(remove_unused_layers no)
			(net "Net_57")
			(clearance 0.254)
			(thermal_gap 0.254)
		)
		(pad "S11" thru_hole oval
			(at 0 2.13995 180)
			(size 0.6096 0.8128)
			(drill 0.399796)
			(layers "*.Cu" "*.Mask")
			(remove_unused_layers no)
			(net "Net_42")
			(clearance 0.254)
			(thermal_gap 0.254)
		)
		(pad "S12" thru_hole oval
			(at -0.8001 2.13995 180)
			(size 0.6096 0.8128)
			(drill 0.399796)
			(layers "*.Cu" "*.Mask")
			(remove_unused_layers no)
			(net "Net_56")
			(clearance 0.254)
			(thermal_gap 0.254)
		)
		(pad "S13" thru_hole oval
			(at -1.6002 2.13995 180)
			(size 0.6096 0.8128)
			(drill 0.399796)
			(layers "*.Cu" "*.Mask")
			(remove_unused_layers no)
			(net "Net_55")
			(clearance 0.254)
			(thermal_gap 0.254)
		)
		(pad "S14" thru_hole oval
			(at -2.4003 2.13995 180)
			(size 0.6096 0.8128)
			(drill 0.399796)
			(layers "*.Cu" "*.Mask")
			(remove_unused_layers no)
			(net "GND")
			(clearance 0.254)
			(thermal_gap 0.254)
		)
	)
)
